# S9S_MB_2U (Grand Teton) — schematic netlist excerpt (pin names and nets, part order shuffled) for the footprints in the layout excerpt that follows; sources: Cadence DE-HDL packaged netlist, KiCad conversion of 03242023_DA0F0TMBIJ0_F0T_Motherboard_J_brd_V01_OCP.brd

R962  Q_RES  33.2 1% CHIP  pkg 0402LF  page 235 : A = SMB_PEHPCPU1_GTL_SDA ; B = SMB_PEHPCPU1_GTL_R_SDA
R684  Q_RES  0 5% EMPTY  pkg 0402LF  page 229 : A = I3C_SPD_DDREFGH_CPU0_R_SCL ; B = I3C_SPD_DDREFGH_CPU0_LVC1_R_SCL

(kicad_pcb
	(version 20260206)
	(generator "pcbnew")
	(generator_version "10.0")
	(general
		(thickness 1.6)
		(legacy_teardrops no)
	)
	(paper "A4")
	(title_block
		(title "03242023_DA0F0TMBIJ0_F0T_Motherboard_J_brd_V01_OCP.brd")
		(comment 1 "Grand Teton / footprints 5606-5607 of 6105")
	)
	(layers
		(0 "F.Cu" signal "TOP")
		(4 "In1.Cu" signal "GND")
		(6 "In2.Cu" signal "IN1")
		(8 "In3.Cu" signal "GND1")
		(10 "In4.Cu" signal "IN2")
		(12 "In5.Cu" signal "GND2")
		(14 "In6.Cu" signal "IN3")
		(16 "In7.Cu" signal "GND3")
		(18 "In8.Cu" signal "VCC")
		(20 "In9.Cu" signal "VCC1")
		(22 "In10.Cu" signal "GND4")
		(24 "In11.Cu" signal "IN4")
		(26 "In12.Cu" signal "GND5")
		(28 "In13.Cu" signal "IN5")
		(30 "In14.Cu" signal "GND6")
		(32 "In15.Cu" signal "IN6")
		(34 "In16.Cu" signal "GND7")
		(2 "B.Cu" signal "BOTTOM")
		(9 "F.Adhes" user "F.Adhesive")
		(11 "B.Adhes" user "B.Adhesive")
		(13 "F.Paste" user "Package Geometry/Pastemask Top")
		(15 "B.Paste" user "Package Geometry/Pastemask Bottom")
		(5 "F.SilkS" user "Ref Des/Silkscreen Top")
		(7 "B.SilkS" user "Ref Des/Silkscreen Bottom")
		(1 "F.Mask" user "Board Geometry/Soldermask Top")
		(3 "B.Mask" user "Board Geometry/Soldermask Bottom")
		(17 "Dwgs.User" user "User.Drawings")
		(19 "Cmts.User" user "User.Comments")
		(21 "Eco1.User" user "User.Eco1")
		(23 "Eco2.User" user "User.Eco2")
		(25 "Edge.Cuts" user "Board Geometry/Outline")
		(27 "Margin" user)
		(31 "F.CrtYd" user "Package Geometry/Place Bound Top")
		(29 "B.CrtYd" user "Package Geometry/Place Bound Bottom")
		(35 "F.Fab" user "Ref Des/Assembly Top")
		(33 "B.Fab" user "Ref Des/Assembly Bottom")
	)
	(footprint ""
		(layer "B.Cu")
		(at 154.21102 -227.427536 180)
		(property "Reference" "R962"
			(at 0 0 0)
			(layer "B.SilkS")
			(hide yes)
			(effects
				(font
					(size 1.27 1.27)
				)
				(justify mirror)
			)
		)
		(property "Value" ""
			(at 0 0 0)
			(layer "B.Fab")
			(effects
				(font
					(size 1.27 1.27)
				)
				(justify mirror)
			)
		)
		(duplicate_pad_numbers_are_jumpers no)
		(fp_line
			(start 0.7874 0.4064)
			(end 0.7874 -0.4064)
			(stroke
				(width 0.1524)
				(type default)
			)
			(layer "B.SilkS")
		)
		(fp_line
			(start 0.7874 -0.4064)
			(end -0.7874 -0.4064)
			(stroke
				(width 0.1524)
				(type default)
			)
			(layer "B.SilkS")
		)
		(fp_line
			(start -0.7874 0.4064)
			(end 0.7874 0.4064)
			(stroke
				(width 0.1524)
				(type default)
			)
			(layer "B.SilkS")
		)
		(fp_line
			(start -0.7874 -0.4064)
			(end -0.7874 0.4064)
			(stroke
				(width 0.1524)
				(type default)
			)
			(layer "B.SilkS")
		)
		(fp_line
			(start 0.67945 0.3048)
			(end 0.67945 -0.305054)
			(stroke
				(width 0.1)
				(type default)
			)
			(layer "B.Fab")
		)
		(fp_line
			(start 0.67945 -0.305054)
			(end 0.12065 -0.305054)
			(stroke
				(width 0.1)
				(type default)
			)
			(layer "B.Fab")
		)
		(fp_line
			(start 0.12065 0.3048)
			(end 0.67945 0.3048)
			(stroke
				(width 0.1)
				(type default)
			)
			(layer "B.Fab")
		)
		(fp_line
			(start 0.12065 0.2794)
			(end 0.12065 0.3048)
			(stroke
				(width 0.1)
				(type default)
			)
			(layer "B.Fab")
		)
		(fp_line
			(start 0.12065 -0.2794)
			(end -0.12065 -0.2794)
			(stroke
				(width 0.1)
				(type default)
			)
			(layer "B.Fab")
		)
		(fp_line
			(start 0.12065 -0.305054)
			(end 0.12065 -0.2794)
			(stroke
				(width 0.1)
				(type default)
			)
			(layer "B.Fab")
		)
		(fp_line
			(start -0.120396 0.3048)
			(end -0.120396 0.2794)
			(stroke
				(width 0.1)
				(type default)
			)
			(layer "B.Fab")
		)
		(fp_line
			(start -0.120396 0.2794)
			(end 0.12065 0.2794)
			(stroke
				(width 0.1)
				(type default)
			)
			(layer "B.Fab")
		)
		(fp_line
			(start -0.12065 -0.2794)
			(end -0.12065 -0.3048)
			(stroke
				(width 0.1)
				(type default)
			)
			(layer "B.Fab")
		)
		(fp_line
			(start -0.12065 -0.3048)
			(end -0.67945 -0.3048)
			(stroke
				(width 0.1)
				(type default)
			)
			(layer "B.Fab")
		)
		(fp_line
			(start -0.67945 0.3048)
			(end -0.120396 0.3048)
			(stroke
				(width 0.1)
				(type default)
			)
			(layer "B.Fab")
		)
		(fp_line
			(start -0.67945 -0.3048)
			(end -0.67945 0.3048)
			(stroke
				(width 0.1)
				(type default)
			)
			(layer "B.Fab")
		)
		(pad "1" smd circle
			(at 0.40005 0)
			(size 0 0)
			(layers "B.Cu" "B.Mask" "B.Paste")
			(net "SMB_PEHPCPU1_GTL_SDA")
		)
		(pad "2" smd circle
			(at -0.40005 0)
			(size 0 0)
			(layers "B.Cu" "B.Mask" "B.Paste")
			(net "SMB_PEHPCPU1_GTL_R_SDA")
		)
	)
	(footprint ""
		(layer "B.Cu")
		(at 304.138584 -153.501344 -90)
		(property "Reference" "R684"
			(at 0 0 90)
			(layer "B.SilkS")
			(hide yes)
			(effects
				(font
					(size 1.27 1.27)
				)
				(justify mirror)
			)
		)
		(property "Value" ""
			(at 0 0 90)
			(layer "B.Fab")
			(effects
				(font
					(size 1.27 1.27)
				)
				(justify mirror)
			)
		)
		(duplicate_pad_numbers_are_jumpers no)
		(fp_line
			(start -0.7874 0.4064)
			(end 0.7874 0.4064)
			(stroke
				(width 0.1524)
				(type default)
			)
			(layer "B.SilkS")
		)
		(fp_line
			(start 0.7874 0.4064)
			(end 0.7874 -0.4064)
			(stroke
				(width 0.1524)
				(type default)
			)
			(layer "B.SilkS")
		)
		(fp_line
			(start -0.7874 -0.4064)
			(end -0.7874 0.4064)
			(stroke
				(width 0.1524)
				(type default)
			)
			(layer "B.SilkS")
		)
		(fp_line
			(start 0.7874 -0.4064)
			(end -0.7874 -0.4064)
			(stroke
				(width 0.1524)
				(type default)
			)
			(layer "B.SilkS")
		)
		(fp_line
			(start -0.67945 0.3048)
			(end -0.120396 0.3048)
			(stroke
				(width 0.1)
				(type default)
			)
			(layer "B.Fab")
		)
		(fp_line
			(start -0.120396 0.3048)
			(end -0.120396 0.2794)
			(stroke
				(width 0.1)
				(type default)
			)
			(layer "B.Fab")
		)
		(fp_line
			(start 0.12065 0.3048)
			(end 0.67945 0.3048)
			(stroke
				(width 0.1)
				(type default)
			)
			(layer "B.Fab")
		)
		(fp_line
			(start 0.67945 0.3048)
			(end 0.67945 -0.305054)
			(stroke
				(width 0.1)
				(type default)
			)
			(layer "B.Fab")
		)
		(fp_line
			(start -0.120396 0.2794)
			(end 0.12065 0.2794)
			(stroke
				(width 0.1)
				(type default)
			)
			(layer "B.Fab")
		)
		(fp_line
			(start 0.12065 0.2794)
			(end 0.12065 0.3048)
			(stroke
				(width 0.1)
				(type default)
			)
			(layer "B.Fab")
		)
		(fp_line
			(start -0.12065 -0.2794)
			(end -0.12065 -0.3048)
			(stroke
				(width 0.1)
				(type default)
			)
			(layer "B.Fab")
		)
		(fp_line
			(start 0.12065 -0.2794)
			(end -0.12065 -0.2794)
			(stroke
				(width 0.1)
				(type default)
			)
			(layer "B.Fab")
		)
		(fp_line
			(start -0.67945 -0.3048)
			(end -0.67945 0.3048)
			(stroke
				(width 0.1)
				(type default)
			)
			(layer "B.Fab")
		)
		(fp_line
			(start -0.12065 -0.3048)
			(end -0.67945 -0.3048)
			(stroke
				(width 0.1)
				(type default)
			)
			(layer "B.Fab")
		)
		(fp_line
			(start 0.12065 -0.305054)
			(end 0.12065 -0.2794)
			(stroke
				(width 0.1)
				(type default)
			)
			(layer "B.Fab")
		)
		(fp_line
			(start 0.67945 -0.305054)
			(end 0.12065 -0.305054)
			(stroke
				(width 0.1)
				(type default)
			)
			(layer "B.Fab")
		)
		(pad "1" smd circle
			(at 0.40005 0 90)
			(size 0 0)
			(layers "B.Cu" "B.Mask" "B.Paste")
			(net "I3C_SPD_DDREFGH_CPU0_R_SCL")
		)
		(pad "2" smd circle
			(at -0.40005 0 90)
			(size 0 0)
			(layers "B.Cu" "B.Mask" "B.Paste")
			(net "I3C_SPD_DDREFGH_CPU0_LVC1_R_SCL")
		)
	)
)
